(kicad_pcb
	(version 20260206)
	(generator "pcbnew")
	(generator_version "10.0")
	(general
		(thickness 1.6)
		(legacy_teardrops no)
	)
	(paper "A4")
	(title_block
		(title "Bryce Canyon_IOM_IOC_16318-2_OCP.brd")
		(comment 1 "Bryce Canyon / footprints 459-464 of 1605")
	)
	(layers
		(0 "F.Cu" signal "TOP")
		(4 "In1.Cu" signal "L2GND")
		(6 "In2.Cu" signal "L3")
		(8 "In3.Cu" signal "L4VCC")
		(10 "In4.Cu" signal "L5VCC")
		(12 "In5.Cu" signal "L6")
		(14 "In6.Cu" signal "L7GND")
		(2 "B.Cu" signal "BOTTOM")
		(9 "F.Adhes" user "F.Adhesive")
		(11 "B.Adhes" user "B.Adhesive")
		(13 "F.Paste" user "Package Geometry/Pastemask Top")
		(15 "B.Paste" user "Package Geometry/Pastemask Bottom")
		(5 "F.SilkS" user "Ref Des/Silkscreen Top")
		(7 "B.SilkS" user "Ref Des/Silkscreen Bottom")
		(1 "F.Mask" user "Board Geometry/Soldermask Top")
		(3 "B.Mask" user "Board Geometry/Soldermask Bottom")
		(17 "Dwgs.User" user "User.Drawings")
		(19 "Cmts.User" user "User.Comments")
		(21 "Eco1.User" user "User.Eco1")
		(23 "Eco2.User" user "User.Eco2")
		(25 "Edge.Cuts" user "Board Geometry/Outline")
		(27 "Margin" user)
		(31 "F.CrtYd" user "Package Geometry/Place Bound Top")
		(29 "B.CrtYd" user "Package Geometry/Place Bound Bottom")
		(35 "F.Fab" user "Ref Des/Assembly Top")
		(33 "B.Fab" user "Ref Des/Assembly Bottom")
	)
	(footprint ""
		(layer "F.Cu")
		(at 205.139036 -122.1486 90)
		(property "Reference" "R545"
			(at 0 0 90)
			(layer "F.SilkS")
			(hide yes)
			(effects
				(font
					(size 1.27 1.27)
				)
			)
		)
		(property "Value" "4K75R2F-1-GP"
			(at 0.064008 -3.993896 90)
			(unlocked yes)
			(layer "F.Fab")
			(hide yes)
			(effects
				(font
					(size 1.016 1.016)
					(thickness 0.1524)
				)
			)
		)
		(property "Device Type" "R402H16"
			(at 0.064008 -5.517896 90)
			(unlocked yes)
			(layer "F.Fab")
			(hide yes)
			(effects
				(font
					(size 1.016 1.016)
					(thickness 0.1524)
				)
			)
		)
		(duplicate_pad_numbers_are_jumpers no)
		(fp_line
			(start 0.508 -0.9398)
			(end -0.508 -0.9398)
			(stroke
				(width 0.1524)
				(type default)
			)
			(layer "F.SilkS")
		)
		(fp_line
			(start -0.508 -0.9398)
			(end -0.508 0.9398)
			(stroke
				(width 0.1524)
				(type default)
			)
			(layer "F.SilkS")
		)
		(fp_rect
			(start -0.508 0.9398)
			(end 0.508 -0.9398)
			(stroke
				(width 0)
				(type default)
			)
			(fill no)
			(layer "F.CrtYd")
		)
		(fp_rect
			(start -0.508 0.9398)
			(end 0.508 -0.9398)
			(stroke
				(width 0)
				(type default)
			)
			(fill no)
			(layer "F.Fab")
		)
		(pad "1" smd custom
			(at 0 -0.4445 90)
			(size 0.1397 0.1397)
			(layers "F.Cu" "F.Mask" "F.Paste")
			(net "TPS74801_P1V5_FB")
			(options
				(clearance outline)
				(anchor circle)
			)
			(primitives
				(gr_poly
					(pts
						(arc
							(start -0.1778 -0.2794)
							(mid -0.249642 -0.249642)
							(end -0.2794 -0.1778)
						)
						(arc
							(start -0.2794 0.1778)
							(mid -0.249642 0.249642)
							(end -0.1778 0.2794)
						)
						(arc
							(start 0.1778 0.2794)
							(mid 0.249642 0.249642)
							(end 0.2794 0.1778)
						)
						(arc
							(start 0.2794 -0.1778)
							(mid 0.249642 -0.249642)
							(end 0.1778 -0.2794)
						)
					)
					(width 0)
					(fill yes)
				)
			)
		)
		(pad "2" smd custom
			(at 0 0.4445 90)
			(size 0.1397 0.1397)
			(layers "F.Cu" "F.Mask" "F.Paste")
			(net "GND")
			(options
				(clearance outline)
				(anchor circle)
			)
			(primitives
				(gr_poly
					(pts
						(arc
							(start -0.1778 -0.2794)
							(mid -0.249642 -0.249642)
							(end -0.2794 -0.1778)
						)
						(arc
							(start -0.2794 0.1778)
							(mid -0.249642 0.249642)
							(end -0.1778 0.2794)
						)
						(arc
							(start 0.1778 0.2794)
							(mid 0.249642 0.249642)
							(end 0.2794 0.1778)
						)
						(arc
							(start 0.2794 -0.1778)
							(mid 0.249642 -0.249642)
							(end 0.1778 -0.2794)
						)
					)
					(width 0)
					(fill yes)
				)
			)
		)
	)
	(footprint ""
		(layer "F.Cu")
		(at 181.229 -90.9066)
		(property "Reference" "R642"
			(at 0 0 0)
			(layer "F.SilkS")
			(hide yes)
			(effects
				(font
					(size 1.27 1.27)
				)
			)
		)
		(property "Value" "4K7R2F-GP"
			(at 0.064008 -3.993896 0)
			(unlocked yes)
			(layer "F.Fab")
			(hide yes)
			(effects
				(font
					(size 1.016 1.016)
					(thickness 0.1524)
				)
			)
		)
		(property "Device Type" "R402H16"
			(at 0.064008 -5.517896 0)
			(unlocked yes)
			(layer "F.Fab")
			(hide yes)
			(effects
				(font
					(size 1.016 1.016)
					(thickness 0.1524)
				)
			)
		)
		(duplicate_pad_numbers_are_jumpers no)
		(fp_line
			(start -0.508 -0.9398)
			(end -0.508 0.9398)
			(stroke
				(width 0.1524)
				(type default)
			)
			(layer "F.SilkS")
		)
		(fp_line
			(start 0.508 -0.9398)
			(end -0.508 -0.9398)
			(stroke
				(width 0.1524)
				(type default)
			)
			(layer "F.SilkS")
		)
		(fp_rect
			(start -0.508 0.9398)
			(end 0.508 -0.9398)
			(stroke
				(width 0)
				(type default)
			)
			(fill no)
			(layer "F.CrtYd")
		)
		(fp_rect
			(start -0.508 0.9398)
			(end 0.508 -0.9398)
			(stroke
				(width 0)
				(type default)
			)
			(fill no)
			(layer "F.Fab")
		)
		(pad "1" smd custom
			(at 0 -0.4445)
			(size 0.1397 0.1397)
			(layers "F.Cu" "F.Mask" "F.Paste")
			(net "P1V8")
			(options
				(clearance outline)
				(anchor circle)
			)
			(primitives
				(gr_poly
					(pts
						(arc
							(start -0.1778 -0.2794)
							(mid -0.249642 -0.249642)
							(end -0.2794 -0.1778)
						)
						(arc
							(start -0.2794 0.1778)
							(mid -0.249642 0.249642)
							(end -0.1778 0.2794)
						)
						(arc
							(start 0.1778 0.2794)
							(mid 0.249642 0.249642)
							(end 0.2794 0.1778)
						)
						(arc
							(start 0.2794 -0.1778)
							(mid 0.249642 -0.249642)
							(end 0.1778 -0.2794)
						)
					)
					(width 0)
					(fill yes)
				)
			)
		)
		(pad "2" smd custom
			(at 0 0.4445)
			(size 0.1397 0.1397)
			(layers "F.Cu" "F.Mask" "F.Paste")
			(net "SYS_DBMODE2")
			(options
				(clearance outline)
				(anchor circle)
			)
			(primitives
				(gr_poly
					(pts
						(arc
							(start -0.1778 -0.2794)
							(mid -0.249642 -0.249642)
							(end -0.2794 -0.1778)
						)
						(arc
							(start -0.2794 0.1778)
							(mid -0.249642 0.249642)
							(end -0.1778 0.2794)
						)
						(arc
							(start 0.1778 0.2794)
							(mid 0.249642 0.249642)
							(end 0.2794 0.1778)
						)
						(arc
							(start 0.2794 -0.1778)
							(mid 0.249642 -0.249642)
							(end 0.1778 -0.2794)
						)
					)
					(width 0)
					(fill yes)
				)
			)
		)
	)
	(footprint ""
		(layer "F.Cu")
		(at 82.529934 -144.339818 90)
		(property "Reference" "U105"
			(at 0 0 90)
			(layer "F.SilkS")
			(hide yes)
			(effects
				(font
					(size 1.27 1.27)
				)
			)
		)
		(property "Value" "SN74CBTLV3245APWR-GP"
			(at -0.889 -6.2738 90)
			(unlocked yes)
			(layer "F.Fab")
			(hide yes)
			(effects
				(font
					(size 1.016 1.016)
					(thickness 0.1524)
				)
			)
		)
		(property "Device Type" "TSOIC20H48"
			(at -0.9144 -7.8994 90)
			(unlocked yes)
			(layer "F.Fab")
			(hide yes)
			(effects
				(font
					(size 1.016 1.016)
					(thickness 0.1524)
				)
			)
		)
		(duplicate_pad_numbers_are_jumpers no)
		(fp_line
			(start 3.175 -1.397)
			(end 3.175 1.397)
			(stroke
				(width 0.2032)
				(type default)
			)
			(layer "F.SilkS")
		)
		(fp_line
			(start -3.556 -1.397)
			(end 3.175 -1.397)
			(stroke
				(width 0.2032)
				(type default)
			)
			(layer "F.SilkS")
		)
		(fp_line
			(start -3.556 -1.397)
			(end -3.556 4.064)
			(stroke
				(width 0.2032)
				(type default)
			)
			(layer "F.SilkS")
		)
		(fp_line
			(start -2.667 0)
			(end -3.556 -0.889)
			(stroke
				(width 0.2032)
				(type default)
			)
			(layer "F.SilkS")
		)
		(fp_line
			(start -2.667 0)
			(end -3.556 0.889)
			(stroke
				(width 0.2032)
				(type default)
			)
			(layer "F.SilkS")
		)
		(fp_line
			(start 3.175 1.397)
			(end -3.556 1.397)
			(stroke
				(width 0.2032)
				(type default)
			)
			(layer "F.SilkS")
		)
		(fp_line
			(start -3.556 1.397)
			(end -3.556 1.778)
			(stroke
				(width 0.2032)
				(type default)
			)
			(layer "F.SilkS")
		)
		(fp_line
			(start -3.556 4.064)
			(end -3.556 1.778)
			(stroke
				(width 0.508)
				(type default)
			)
			(layer "F.SilkS")
		)
		(fp_poly
			(pts
				(xy -3.25628 -1.8542) (xy 3.25628 -1.8542) (xy 3.25628 1.8542) (xy -3.25628 1.8542)
			)
			(stroke
				(width 0)
				(type default)
			)
			(fill yes)
			(layer "F.SilkS")
		)
		(fp_rect
			(start -3.556 3.81)
			(end 3.556 -3.81)
			(stroke
				(width 0)
				(type default)
			)
			(fill no)
			(layer "F.CrtYd")
		)
		(fp_poly
			(pts
				(xy -3.556 -3.81) (xy 3.556 -3.81) (xy 3.556 3.81) (xy -3.556 3.81)
			)
			(stroke
				(width 0)
				(type default)
			)
			(fill no)
			(layer "F.Fab")
		)
		(pad "1" smd rect
			(at -2.92608 2.8194 90)
			(size 0.3556 1.524)
			(layers "F.Cu" "F.Mask" "F.Paste")
			(net "Net_133")
		)
		(pad "2" smd rect
			(at -2.27584 2.8194 90)
			(size 0.3556 1.524)
			(layers "F.Cu" "F.Mask" "F.Paste")
			(net "I2C_EXP_LOC_SCL_OUT")
		)
		(pad "3" smd rect
			(at -1.6256 2.8194 90)
			(size 0.3556 1.524)
			(layers "F.Cu" "F.Mask" "F.Paste")
			(net "I2C_EXP_LOC_SDA_OUT")
		)
		(pad "4" smd rect
			(at -0.97536 2.8194 90)
			(size 0.3556 1.524)
			(layers "F.Cu" "F.Mask" "F.Paste")
			(net "I2C_EXP_RMT_SCL_OUT")
		)
		(pad "5" smd rect
			(at -0.32512 2.8194 90)
			(size 0.3556 1.524)
			(layers "F.Cu" "F.Mask" "F.Paste")
			(net "I2C_EXP_RMT_SDA_OUT")
		)
		(pad "6" smd rect
			(at 0.32512 2.8194 90)
			(size 0.3556 1.524)
			(layers "F.Cu" "F.Mask" "F.Paste")
			(net "I2C_SCC_SCL_OUT")
		)
		(pad "7" smd rect
			(at 0.97536 2.8194 90)
			(size 0.3556 1.524)
			(layers "F.Cu" "F.Mask" "F.Paste")
			(net "I2C_SCC_SDA_OUT")
		)
		(pad "8" smd rect
			(at 1.6256 2.8194 90)
			(size 0.3556 1.524)
			(layers "F.Cu" "F.Mask" "F.Paste")
			(net "I2C_DPB_SCL_OUT")
		)
		(pad "9" smd rect
			(at 2.27584 2.8194 90)
			(size 0.3556 1.524)
			(layers "F.Cu" "F.Mask" "F.Paste")
			(net "I2C_DPB_SDA_OUT")
		)
		(pad "10" smd rect
			(at 2.92608 2.8194 90)
			(size 0.3556 1.524)
			(layers "F.Cu" "F.Mask" "F.Paste")
			(net "GND")
		)
		(pad "11" smd rect
			(at 2.92608 -2.8194 90)
			(size 0.3556 1.524)
			(layers "F.Cu" "F.Mask" "F.Paste")
			(net "I2C_DPB_SDA_R")
		)
		(pad "12" smd rect
			(at 2.27584 -2.8194 90)
			(size 0.3556 1.524)
			(layers "F.Cu" "F.Mask" "F.Paste")
			(net "I2C_DPB_SCL_R")
		)
		(pad "13" smd rect
			(at 1.6256 -2.8194 90)
			(size 0.3556 1.524)
			(layers "F.Cu" "F.Mask" "F.Paste")
			(net "I2C_SCC_SDA_R")
		)
		(pad "14" smd rect
			(at 0.97536 -2.8194 90)
			(size 0.3556 1.524)
			(layers "F.Cu" "F.Mask" "F.Paste")
			(net "I2C_SCC_SCL_R")
		)
		(pad "15" smd rect
			(at 0.32512 -2.8194 90)
			(size 0.3556 1.524)
			(layers "F.Cu" "F.Mask" "F.Paste")
			(net "I2C_EXP_RMT_SDA_R")
		)
		(pad "16" smd rect
			(at -0.32512 -2.8194 90)
			(size 0.3556 1.524)
			(layers "F.Cu" "F.Mask" "F.Paste")
			(net "I2C_EXP_RMT_SCL_R")
		)
		(pad "17" smd rect
			(at -0.97536 -2.8194 90)
			(size 0.3556 1.524)
			(layers "F.Cu" "F.Mask" "F.Paste")
			(net "I2C_EXP_LOC_SDA_R")
		)
		(pad "18" smd rect
			(at -1.6256 -2.8194 90)
			(size 0.3556 1.524)
			(layers "F.Cu" "F.Mask" "F.Paste")
			(net "I2C_EXP_LOC_SCL_R")
		)
		(pad "19" smd rect
			(at -2.27584 -2.8194 90)
			(size 0.3556 1.524)
			(layers "F.Cu" "F.Mask" "F.Paste")
			(net "PWRGD_P3V3_STBY_N_R1")
		)
		(pad "20" smd rect
			(at -2.92608 -2.8194 90)
			(size 0.3556 1.524)
			(layers "F.Cu" "F.Mask" "F.Paste")
			(net "P3V3_STBY")
		)
	)
	(footprint ""
		(layer "F.Cu")
		(at 93.411548 -36.423854 180)
		(property "Reference" "C325"
			(at 0 0 180)
			(layer "F.SilkS")
			(hide yes)
			(effects
				(font
					(size 1.27 1.27)
				)
			)
		)
		(property "Value" "ST150U16VDM-3-GP"
			(at 0 -9.6012 180)
			(unlocked yes)
			(layer "F.Fab")
			(hide yes)
			(effects
				(font
					(size 1.016 1.016)
					(thickness 0.1524)
				)
			)
		)
		(property "Device Type" "CT7343H119"
			(at 0 -11.1252 180)
			(unlocked yes)
			(layer "F.Fab")
			(hide yes)
			(effects
				(font
					(size 1.016 1.016)
					(thickness 0.1524)
				)
			)
		)
		(duplicate_pad_numbers_are_jumpers no)
		(fp_line
			(start 2.286 4.8768)
			(end -2.286 4.8768)
			(stroke
				(width 0.1524)
				(type default)
			)
			(layer "F.SilkS")
		)
		(fp_line
			(start 2.286 2.032)
			(end 2.286 4.8768)
			(stroke
				(width 0.1524)
				(type default)
			)
			(layer "F.SilkS")
		)
		(fp_line
			(start 2.286 -2.032)
			(end 2.286 -4.8768)
			(stroke
				(width 0.1524)
				(type default)
			)
			(layer "F.SilkS")
		)
		(fp_line
			(start 2.286 -4.8768)
			(end -2.286 -4.8768)
			(stroke
				(width 0.1524)
				(type default)
			)
			(layer "F.SilkS")
		)
		(fp_line
			(start 2.1082 -4.699)
			(end -2.1082 -4.699)
			(stroke
				(width 0.508)
				(type default)
			)
			(layer "F.SilkS")
		)
		(fp_line
			(start -2.286 4.8768)
			(end -2.286 2.032)
			(stroke
				(width 0.1524)
				(type default)
			)
			(layer "F.SilkS")
		)
		(fp_line
			(start -2.286 -4.8768)
			(end -2.286 -2.032)
			(stroke
				(width 0.1524)
				(type default)
			)
			(layer "F.SilkS")
		)
		(fp_rect
			(start -2.1463 3.6449)
			(end 2.1463 -3.6449)
			(stroke
				(width 0)
				(type default)
			)
			(fill no)
			(layer "F.CrtYd")
		)
		(fp_poly
			(pts
				(xy -2.54 4.953) (xy -2.54 4.2926) (xy -3.81 4.2926) (xy -3.81 -4.2926) (xy -2.54 -4.2926) (xy -2.54 -4.953)
				(xy 2.54 -4.953) (xy 2.54 -4.2926) (xy 3.81 -4.2926) (xy 3.81 -1.6256) (xy 2.1463 -1.6256) (xy 2.1463 -3.6449)
				(xy -2.1463 -3.6449) (xy -2.1463 3.6449) (xy 2.1463 3.6449) (xy 2.1463 -1.6129) (xy 3.81 -1.6129)
				(xy 3.81 4.2926) (xy 2.54 4.2926) (xy 2.54 4.953)
			)
			(stroke
				(width 0)
				(type default)
			)
			(fill no)
			(layer "F.CrtYd")
		)
		(fp_rect
			(start 2.54 4.2926)
			(end 3.81 -4.2926)
			(stroke
				(width 0)
				(type default)
			)
			(fill no)
			(layer "F.Fab")
		)
		(fp_rect
			(start -2.54 4.953)
			(end 2.54 -4.953)
			(stroke
				(width 0)
				(type default)
			)
			(fill no)
			(layer "F.Fab")
		)
		(fp_rect
			(start -3.81 4.2926)
			(end -2.54 -4.2926)
			(stroke
				(width 0)
				(type default)
			)
			(fill no)
			(layer "F.Fab")
		)
		(pad "1" smd rect
			(at 0 -3.1496 180)
			(size 2.413 2.286)
			(layers "F.Cu" "F.Mask" "F.Paste")
			(net "P5V_USB")
		)
		(pad "2" smd rect
			(at 0 3.1496 180)
			(size 2.413 2.286)
			(layers "F.Cu" "F.Mask" "F.Paste")
			(net "GND")
		)
		(zone
			(layer "F.Cu")
			(hatch none 0.5)
			(connect_pads
				(clearance 0)
			)
			(min_thickness 0.25)
			(keepout
				(tracks allowed)
				(vias not_allowed)
				(pads allowed)
				(copperpour not_allowed)
				(footprints allowed)
			)
			(placement
				(enabled no)
				(sheetname "")
			)
			(fill
				(thermal_gap 0.5)
				(thermal_bridge_width 0.5)
				(island_removal_mode 0)
			)
			(polygon
				(pts
					(xy 91.900248 -34.734754) (xy 91.900248 -31.826454) (xy 94.922848 -31.826454) (xy 94.922848 -34.722054)
					(xy 94.922848 -35.052254) (xy 91.900248 -35.052254)
				)
			)
		)
		(zone
			(layer "F.Cu")
			(hatch none 0.5)
			(connect_pads
				(clearance 0)
			)
			(min_thickness 0.25)
			(keepout
				(tracks allowed)
				(vias not_allowed)
				(pads allowed)
				(copperpour not_allowed)
				(footprints allowed)
			)
			(placement
				(enabled no)
				(sheetname "")
			)
			(fill
				(thermal_gap 0.5)
				(thermal_bridge_width 0.5)
				(island_removal_mode 0)
			)
			(polygon
				(pts
					(xy 94.922848 -41.021254) (xy 91.900248 -41.021254) (xy 91.900248 -38.125654) (xy 91.900248 -37.795454)
					(xy 94.922848 -37.795454) (xy 94.922848 -38.125654)
				)
			)
		)
	)
	(footprint ""
		(layer "F.Cu")
		(at 60.616592 -131.296156 180)
		(property "Reference" "R290"
			(at 0 0 180)
			(layer "F.SilkS")
			(hide yes)
			(effects
				(font
					(size 1.27 1.27)
				)
			)
		)
		(property "Value" "0R2J-2-GP"
			(at 0.064008 -3.993896 180)
			(unlocked yes)
			(layer "F.Fab")
			(hide yes)
			(effects
				(font
					(size 1.016 1.016)
					(thickness 0.1524)
				)
			)
		)
		(property "Device Type" "R402H16"
			(at 0.064008 -5.517896 180)
			(unlocked yes)
			(layer "F.Fab")
			(hide yes)
			(effects
				(font
					(size 1.016 1.016)
					(thickness 0.1524)
				)
			)
		)
		(duplicate_pad_numbers_are_jumpers no)
		(fp_line
			(start 0.508 -0.9398)
			(end -0.508 -0.9398)
			(stroke
				(width 0.1524)
				(type default)
			)
			(layer "F.SilkS")
		)
		(fp_line
			(start -0.508 -0.9398)
			(end -0.508 0.9398)
			(stroke
				(width 0.1524)
				(type default)
			)
			(layer "F.SilkS")
		)
		(fp_rect
			(start -0.508 0.9398)
			(end 0.508 -0.9398)
			(stroke
				(width 0)
				(type default)
			)
			(fill no)
			(layer "F.CrtYd")
		)
		(fp_rect
			(start -0.508 0.9398)
			(end 0.508 -0.9398)
			(stroke
				(width 0)
				(type default)
			)
			(fill no)
			(layer "F.Fab")
		)
		(pad "1" smd custom
			(at 0 -0.4445 180)
			(size 0.1397 0.1397)
			(layers "F.Cu" "F.Mask" "F.Paste")
			(net "SCC_STBY_PWR_EN")
			(options
				(clearance outline)
				(anchor circle)
			)
			(primitives
				(gr_poly
					(pts
						(arc
							(start -0.1778 -0.2794)
							(mid -0.249642 -0.249642)
							(end -0.2794 -0.1778)
						)
						(arc
							(start -0.2794 0.1778)
							(mid -0.249642 0.249642)
							(end -0.1778 0.2794)
						)
						(arc
							(start 0.1778 0.2794)
							(mid 0.249642 0.249642)
							(end 0.2794 0.1778)
						)
						(arc
							(start 0.2794 -0.1778)
							(mid 0.249642 -0.249642)
							(end 0.1778 -0.2794)
						)
					)
					(width 0)
					(fill yes)
				)
			)
		)
		(pad "2" smd custom
			(at 0 0.4445 180)
			(size 0.1397 0.1397)
			(layers "F.Cu" "F.Mask" "F.Paste")
			(net "SCC_PWR_EN_R")
			(options
				(clearance outline)
				(anchor circle)
			)
			(primitives
				(gr_poly
					(pts
						(arc
							(start -0.1778 -0.2794)
							(mid -0.249642 -0.249642)
							(end -0.2794 -0.1778)
						)
						(arc
							(start -0.2794 0.1778)
							(mid -0.249642 0.249642)
							(end -0.1778 0.2794)
						)
						(arc
							(start 0.1778 0.2794)
							(mid 0.249642 0.249642)
							(end 0.2794 0.1778)
						)
						(arc
							(start 0.2794 -0.1778)
							(mid 0.249642 -0.249642)
							(end 0.1778 -0.2794)
						)
					)
					(width 0)
					(fill yes)
				)
			)
		)
	)
	(footprint ""
		(layer "F.Cu")
		(at 172.2374 -38.481)
		(property "Reference" "TP173"
			(at 0 0 0)
			(layer "F.SilkS")
			(hide yes)
			(effects
				(font
					(size 1.27 1.27)
				)
			)
		)
		(property "Value" "TPAD28-2-GP"
			(at -0.0127 -1.6637 0)
			(unlocked yes)
			(layer "F.Fab")
			(hide yes)
			(effects
				(font
					(size 1.016 1.016)
					(thickness 0.1524)
				)
			)
		)
		(property "Device Type" "TPAD28"
			(at -0.0127 -3.1877 0)
			(unlocked yes)
			(layer "F.Fab")
			(hide yes)
			(effects
				(font
					(size 1.016 1.016)
					(thickness 0.1524)
				)
			)
		)
		(duplicate_pad_numbers_are_jumpers no)
		(fp_poly
			(pts
				(arc
					(start 0.3556 0)
					(mid -0.3556 0)
					(end 0.3556 0)
				)
			)
			(stroke
				(width 0)
				(type default)
			)
			(fill no)
			(layer "F.CrtYd")
		)
		(fp_poly
			(pts
				(arc
					(start 0.6096 0)
					(mid -0.6096 0)
					(end 0.6096 0)
				)
			)
			(stroke
				(width 0)
				(type default)
			)
			(fill no)
			(layer "F.Fab")
		)
		(pad "1" smd circle
			(at 0 0)
			(size 0.7112 0.7112)
			(layers "F.Cu" "F.Mask" "F.Paste")
			(net "ZDEF_EXTA_TP_A2")
		)
	)
)
